FILE_TYPE = CONNECTIVITY;
{Allegro Design Entry HDL 17.4-2019 S026 (4007227) 1/17/2022}
"PAGE_NUMBER" = 31;
0"NC";
1"GND\g";
2"GND\g";
3"GND\g";
4"GND\g";
5"GND\g";
6"GND\g";
7"GND\g";
8"GND\g";
9"GND\g";
10"GND\g";
11"GND\g";
12"GND\g";
%"GENOA_SP5"
"28","(-8600,3400)","0","pure_quanta","I19";
;
LOCATION"U25"
$SEC"28"
CDS_SEC"28"
PART_TYPE"SMLF"
MATERIAL"IO"
VALUE"SOCKET6096_13568-001"
CDS_LIB"pure_quanta"
CDS_LMAN_SYM_OUTLINE"-400,3050,400,-3050"
NEEDS_NO_SIZE"TRUE"
PART_NUMBER"DGA^6000030";
"VSS_H34"
$PN"H34"2;
"VSS_H31"
$PN"H31"2;
"VSS_H28"
$PN"H28"2;
"VSS_H25"
$PN"H25"2;
"VSS_H22"
$PN"H22"2;
"VSS_H17"
$PN"H17"2;
"VSS_H15"
$PN"H15"2;
"VSS_H10"
$PN"H10"2;
"VSS_H8"
$PN"H8"2;
"VSS_H3"
$PN"H3"2;
"VSS_G75"
$PN"G75"2;
"VSS_G72"
$PN"G72"2;
"VSS_G70"
$PN"G70"2;
"VSS_G68"
$PN"G68"2;
"VSS_G65"
$PN"G65"2;
"VSS_G63"
$PN"G63"2;
"VSS_G61"
$PN"G61"2;
"VSS_G58"
$PN"G58"2;
"VSS_G56"
$PN"G56"2;
"VSS_G54"
$PN"G54"2;
"VSS_G51"
$PN"G51"2;
"VSS_G48"
$PN"G48"2;
"VSS_G45"
$PN"G45"2;
"VSS_G42"
$PN"G42"2;
"VSS_G34"
$PN"G34"2;
"VSS_G31"
$PN"G31"2;
"VSS_G28"
$PN"G28"2;
"VSS_G25"
$PN"G25"2;
"VSS_G22"
$PN"G22"2;
"VSS_G20"
$PN"G20"2;
"VSS_G18"
$PN"G18"2;
"VSS_G15"
$PN"G15"2;
"VSS_G13"
$PN"G13"2;
"VSS_G11"
$PN"G11"2;
"VSS_G8"
$PN"G8"2;
"VSS_G6"
$PN"G6"2;
"VSS_G4"
$PN"G4"2;
"VSS_G1"
$PN"G1"2;
"VSS_F73"
$PN"F73"2;
"VSS_F71"
$PN"F71"2;
"VSS_F68"
$PN"F68"2;
"VSS_F66"
$PN"F66"2;
"VSS_F64"
$PN"F64"2;
"VSS_F61"
$PN"F61"2;
"VSS_F59"
$PN"F59"2;
"VSS_F57"
$PN"F57"2;
"VSS_F53"
$PN"F53"2;
"VSS_F52"
$PN"F52"2;
"VSS_F50"
$PN"F50"2;
"VSS_F49"
$PN"F49"2;
"VSS_F47"
$PN"F47"2;
"VSS_F46"
$PN"F46"2;
"VSS_F44"
$PN"F44"2;
"VSS_F43"
$PN"F43"2;
"VSS_F41"
$PN"F41"2;
"VSS_F40"
$PN"F40"2;
"VSS_F39"
$PN"F39"2;
"VSS_F37"
$PN"F37"2;
"VSS_F36"
$PN"F36"2;
"VSS_F35"
$PN"F35"2;
"VSS_F33"
$PN"F33"2;
"VSS_F32"
$PN"F32"2;
"VSS_F30"
$PN"F30"2;
"VSS_F29"
$PN"F29"2;
"VSS_F27"
$PN"F27"2;
"VSS_F26"
$PN"F26"2;
"VSS_F24"
$PN"F24"2;
"VSS_F23"
$PN"F23"2;
"VSS_F19"
$PN"F19"2;
"VSS_F17"
$PN"F17"2;
"VSS_F15"
$PN"F15"2;
"VSS_F12"
$PN"F12"2;
"VSS_F10"
$PN"F10"2;
"VSS_F8"
$PN"F8"2;
"VSS_F5"
$PN"F5"2;
"VSS_F3"
$PN"F3"2;
"VSS_E75"
$PN"E75"2;
"VSS_E73"
$PN"E73"2;
"VSS_E72"
$PN"E72"2;
"VSS_E70"
$PN"E70"2;
"VSS_E69"
$PN"E69"2;
"VSS_E68"
$PN"E68"2;
"VSS_E66"
$PN"E66"2;
"VSS_E65"
$PN"E65"2;
"VSS_E63"
$PN"E63"2;
"VSS_E62"
$PN"E62"2;
"VSS_E61"
$PN"E61"2;
"VSS_E59"
$PN"E59"2;
"VSS_E58"
$PN"E58"2;
"VSS_E56"
$PN"E56"2;
"VSS_E55"
$PN"E55"2;
"VSS_E53"
$PN"E53"2;
"VSS_E52"
$PN"E52"2;
"VSS_E21"
$PN"E21"2;
"VSS_E20"
$PN"E20"2;
"VSS_E18"
$PN"E18"2;
"VSS_E17"
$PN"E17"2;
"VSS_E15"
$PN"E15"2;
"VSS_E14"
$PN"E14"2;
"VSS_E13"
$PN"E13"2;
"VSS_E10"
$PN"E10"2;
"VSS_E8"
$PN"E8"1;
"VSS_E7"
$PN"E7"1;
"VSS_E6"
$PN"E6"1;
"VSS_E3"
$PN"E3"1;
"VSS_E1"
$PN"E1"1;
"VSS_D74"
$PN"D74"1;
"VSS_D73"
$PN"D73"1;
"VSS_D71"
$PN"D71"1;
"VSS_D70"
$PN"D70"1;
"VSS_D67"
$PN"D67"1;
"VSS_D66"
$PN"D66"1;
"VSS_D64"
$PN"D64"1;
"VSS_D63"
$PN"D63"1;
"VSS_D61"
$PN"D61"1;
"VSS_D60"
$PN"D60"1;
"VSS_D59"
$PN"D59"1;
"VSS_D57"
$PN"D57"1;
"VSS_D54"
$PN"D54"1;
"VSS_D53"
$PN"D53"1;
"VSS_D52"
$PN"D52"1;
"VSS_D51"
$PN"D51"1;
"VSS_D50"
$PN"D50"1;
"VSS_D49"
$PN"D49"1;
"VSS_D48"
$PN"D48"1;
"VSS_D47"
$PN"D47"1;
"VSS_D46"
$PN"D46"1;
"VSS_D45"
$PN"D45"1;
"VSS_D44"
$PN"D44"1;
"VSS_D43"
$PN"D43"1;
"VSS_D42"
$PN"D42"1;
"VSS_D41"
$PN"D41"1;
"VSS_D40"
$PN"D40"1;
"VSS_D39"
$PN"D39"1;
"VSS_D37"
$PN"D37"1;
"VSS_D35"
$PN"D35"1;
"VSS_D31"
$PN"D31"1;
"VSS_D30"
$PN"D30"1;
"VSS_D29"
$PN"D29"1;
"VSS_D28"
$PN"D28"1;
"VSS_D27"
$PN"D27"1;
"VSS_D26"
$PN"D26"1;
"VSS_D25"
$PN"D25"1;
"VSS_D24"
$PN"D24"1;
"VSS_D21"
$PN"D21"1;
"VSS_D20"
$PN"D20"1;
"VSS_D19"
$PN"D19"1;
"VSS_D17"
$PN"D17"1;
"VSS_D16"
$PN"D16"1;
"VSS_D13"
$PN"D13"1;
"VSS_D12"
$PN"D12"1;
"VSS_D10"
$PN"D10"1;
"VSS_D9"
$PN"D9"1;
"VSS_D6"
$PN"D6"1;
"VSS_D5"
$PN"D5"1;
"VSS_D3"
$PN"D3"1;
"VSS_D2"
$PN"D2"1;
"VSS_C75"
$PN"C75"1;
"VSS_C73"
$PN"C73"1;
"VSS_C71"
$PN"C71"1;
"VSS_C69"
$PN"C69"1;
"VSS_C67"
$PN"C67"1;
"VSS_C64"
$PN"C64"1;
"VSS_C61"
$PN"C61"1;
"VSS_C57"
$PN"C57"1;
"VSS_C56"
$PN"C56"1;
"VSS_C55"
$PN"C55"1;
"VSS_C52"
$PN"C52"1;
"VSS_C49"
$PN"C49"1;
"VSS_C46"
$PN"C46"1;
"VSS_C43"
$PN"C43"1;
"VSS_C40"
$PN"C40"1;
"VSS_C36"
$PN"C36"1;
"VSS_C30"
$PN"C30"1;
"VSS_C27"
$PN"C27"1;
"VSS_C24"
$PN"C24"1;
"VSS_C21"
$PN"C21"1;
"VSS_C15"
$PN"C15"1;
"VSS_C13"
$PN"C13"1;
"VSS_C11"
$PN"C11"1;
"VSS_C10"
$PN"C10"1;
"VSS_C8"
$PN"C8"1;
"VSS_C5"
$PN"C5"1;
"VSS_C1"
$PN"C1"1;
"VSS_B70"
$PN"B70"1;
"VSS_B68"
$PN"B68"1;
"VSS_B65"
$PN"B65"1;
"VSS_B62"
$PN"B62"1;
"VSS_B59"
$PN"B59"1;
"VSS_B55"
$PN"B55"1;
"VSS_B52"
$PN"B52"1;
"VSS_B49"
$PN"B49"1;
"VSS_B46"
$PN"B46"1;
"VSS_B43"
$PN"B43"1;
"VSS_B39"
$PN"B39"1;
"VSS_B37"
$PN"B37"1;
"VSS_B33"
$PN"B33"1;
"VSS_B30"
$PN"B30"1;
"VSS_B27"
$PN"B27"1;
"VSS_B24"
$PN"B24"1;
"VSS_B18"
$PN"B18"1;
"VSS_B13"
$PN"B13"1;
"VSS_B11"
$PN"B11"1;
"VSS_B10"
$PN"B10"1;
"VSS_B8"
$PN"B8"1;
"VSS_B7"
$PN"B7"1;
"VSS_A73"
$PN"A73"1;
"VSS_A72"
$PN"A72"1;
"VSS_A67"
$PN"A67"1;
"VSS_A61"
$PN"A61"1;
"VSS_A53"
$PN"A53"1;
"VSS_A49"
$PN"A49"1;
"VSS_A47"
$PN"A47"1;
"VSS_A44"
$PN"A44"1;
"VSS_A43"
$PN"A43"1;
"VSS_A27"
$PN"A27"1;
"VSS_A21"
$PN"A21"1;
"VSS_A15"
$PN"A15"1;
"VSS_A9"
$PN"A9"1;
"VSS_A3"
$PN"A3"1;
"VSS_J13"
$PN"J13"2;
"VSS_J11"
$PN"J11"2;
"VSS_J8"
$PN"J8"2;
"VSS_J6"
$PN"J6"2;
"VSS_J4"
$PN"J4"2;
"VSS_J1"
$PN"J1"2;
"VSS_H73"
$PN"H73"2;
"VSS_H68"
$PN"H68"2;
"VSS_H66"
$PN"H66"2;
"VSS_H61"
$PN"H61"2;
"VSS_H59"
$PN"H59"2;
"VSS_H54"
$PN"H54"2;
"VSS_H51"
$PN"H51"2;
"VSS_H48"
$PN"H48"2;
"VSS_H45"
$PN"H45"2;
"VSS_H42"
$PN"H42"2;
"VSS_H39"
$PN"H39"2;
"VSS_H37"
$PN"H37"2;
%"GENOA_SP5"
"29","(-7075,3425)","0","pure_quanta","I20";
;
LOCATION"U25"
$SEC"29"
CDS_SEC"29"
PART_TYPE"SMLF"
MATERIAL"IO"
VALUE"SOCKET6096_13568-001"
NEEDS_NO_SIZE"TRUE"
CDS_LMAN_SYM_OUTLINE"-400,3050,400,-3050"
CDS_LIB"pure_quanta"
PART_NUMBER"DGA^6000030";
"VSS_R45"
$PN"R45"4;
"VSS_R42"
$PN"R42"4;
"VSS_R41"
$PN"R41"4;
"VSS_R40"
$PN"R40"4;
"VSS_R36"
$PN"R36"4;
"VSS_R35"
$PN"R35"4;
"VSS_R34"
$PN"R34"4;
"VSS_R31"
$PN"R31"4;
"VSS_R28"
$PN"R28"4;
"VSS_R25"
$PN"R25"4;
"VSS_R22"
$PN"R22"4;
"VSS_R20"
$PN"R20"4;
"VSS_R18"
$PN"R18"4;
"VSS_R15"
$PN"R15"4;
"VSS_R13"
$PN"R13"4;
"VSS_R11"
$PN"R11"4;
"VSS_R8"
$PN"R8"4;
"VSS_R6"
$PN"R6"4;
"VSS_R4"
$PN"R4"4;
"VSS_R1"
$PN"R1"4;
"VSS_P73"
$PN"P73"4;
"VSS_P66"
$PN"P66"4;
"VSS_P61"
$PN"P61"4;
"VSS_P59"
$PN"P59"4;
"VSS_P53"
$PN"P53"4;
"VSS_P52"
$PN"P52"4;
"VSS_P51"
$PN"P51"4;
"VSS_P50"
$PN"P50"4;
"VSS_P49"
$PN"P49"4;
"VSS_P48"
$PN"P48"4;
"VSS_P47"
$PN"P47"4;
"VSS_P46"
$PN"P46"4;
"VSS_P45"
$PN"P45"4;
"VSS_P44"
$PN"P44"4;
"VSS_P43"
$PN"P43"4;
"VSS_P42"
$PN"P42"4;
"VSS_P39"
$PN"P39"4;
"VSS_P37"
$PN"P37"4;
"VSS_P34"
$PN"P34"4;
"VSS_P33"
$PN"P33"4;
"VSS_P32"
$PN"P32"4;
"VSS_P31"
$PN"P31"4;
"VSS_P30"
$PN"P30"4;
"VSS_P29"
$PN"P29"4;
"VSS_P28"
$PN"P28"4;
"VSS_P27"
$PN"P27"4;
"VSS_P26"
$PN"P26"4;
"VSS_P24"
$PN"P24"4;
"VSS_P23"
$PN"P23"4;
"VSS_P17"
$PN"P17"4;
"VSS_P15"
$PN"P15"4;
"VSS_P10"
$PN"P10"4;
"VSS_P8"
$PN"P8"4;
"VSS_P3"
$PN"P3"4;
"VSS_N75"
$PN"N75"4;
"VSS_N72"
$PN"N72"4;
"VSS_N70"
$PN"N70"4;
"VSS_N68"
$PN"N68"4;
"VSS_N65"
$PN"N65"4;
"VSS_N63"
$PN"N63"4;
"VSS_N61"
$PN"N61"4;
"VSS_N58"
$PN"N58"4;
"VSS_N56"
$PN"N56"4;
"VSS_N54"
$PN"N54"4;
"VSS_N51"
$PN"N51"4;
"VSS_N48"
$PN"N48"4;
"VSS_N45"
$PN"N45"4;
"VSS_N42"
$PN"N42"4;
"VSS_N34"
$PN"N34"4;
"VSS_N31"
$PN"N31"4;
"VSS_N28"
$PN"N28"4;
"VSS_N25"
$PN"N25"4;
"VSS_N22"
$PN"N22"4;
"VSS_N20"
$PN"N20"4;
"VSS_N18"
$PN"N18"4;
"VSS_N15"
$PN"N15"4;
"VSS_N13"
$PN"N13"4;
"VSS_N11"
$PN"N11"4;
"VSS_N8"
$PN"N8"4;
"VSS_N6"
$PN"N6"4;
"VSS_N4"
$PN"N4"4;
"VSS_N1"
$PN"N1"3;
"VSS_M73"
$PN"M73"3;
"VSS_M71"
$PN"M71"3;
"VSS_M68"
$PN"M68"3;
"VSS_M66"
$PN"M66"3;
"VSS_M64"
$PN"M64"3;
"VSS_M61"
$PN"M61"3;
"VSS_M59"
$PN"M59"3;
"VSS_M57"
$PN"M57"3;
"VSS_M54"
$PN"M54"3;
"VSS_M51"
$PN"M51"3;
"VSS_M48"
$PN"M48"3;
"VSS_M45"
$PN"M45"3;
"VSS_M42"
$PN"M42"3;
"VSS_M39"
$PN"M39"3;
"VSS_M37"
$PN"M37"3;
"VSS_M34"
$PN"M34"3;
"VSS_M31"
$PN"M31"3;
"VSS_M28"
$PN"M28"3;
"VSS_M25"
$PN"M25"3;
"VSS_M22"
$PN"M22"3;
"VSS_M19"
$PN"M19"3;
"VSS_M17"
$PN"M17"3;
"VSS_M15"
$PN"M15"3;
"VSS_M12"
$PN"M12"3;
"VSS_M10"
$PN"M10"3;
"VSS_M8"
$PN"M8"3;
"VSS_M5"
$PN"M5"3;
"VSS_M3"
$PN"M3"3;
"VSS_L75"
$PN"L75"3;
"VSS_L70"
$PN"L70"3;
"VSS_L68"
$PN"L68"3;
"VSS_L63"
$PN"L63"3;
"VSS_L61"
$PN"L61"3;
"VSS_L56"
$PN"L56"3;
"VSS_L54"
$PN"L54"3;
"VSS_L51"
$PN"L51"3;
"VSS_L48"
$PN"L48"3;
"VSS_L45"
$PN"L45"3;
"VSS_L42"
$PN"L42"3;
"VSS_L41"
$PN"L41"3;
"VSS_L40"
$PN"L40"3;
"VSS_L36"
$PN"L36"3;
"VSS_L35"
$PN"L35"3;
"VSS_L34"
$PN"L34"3;
"VSS_L31"
$PN"L31"3;
"VSS_L28"
$PN"L28"3;
"VSS_L25"
$PN"L25"3;
"VSS_L22"
$PN"L22"3;
"VSS_L20"
$PN"L20"3;
"VSS_L15"
$PN"L15"3;
"VSS_L13"
$PN"L13"3;
"VSS_L8"
$PN"L8"3;
"VSS_L6"
$PN"L6"3;
"VSS_L1"
$PN"L1"3;
"VSS_K73"
$PN"K73"3;
"VSS_K71"
$PN"K71"3;
"VSS_K68"
$PN"K68"3;
"VSS_K66"
$PN"K66"3;
"VSS_K64"
$PN"K64"3;
"VSS_K61"
$PN"K61"3;
"VSS_K57"
$PN"K57"3;
"VSS_K53"
$PN"K53"3;
"VSS_K52"
$PN"K52"3;
"VSS_K51"
$PN"K51"3;
"VSS_K50"
$PN"K50"3;
"VSS_K49"
$PN"K49"3;
"VSS_K48"
$PN"K48"3;
"VSS_K47"
$PN"K47"3;
"VSS_K46"
$PN"K46"3;
"VSS_K45"
$PN"K45"3;
"VSS_K44"
$PN"K44"3;
"VSS_K43"
$PN"K43"3;
"VSS_K42"
$PN"K42"3;
"VSS_K39"
$PN"K39"3;
"VSS_K37"
$PN"K37"3;
"VSS_K34"
$PN"K34"3;
"VSS_K33"
$PN"K33"3;
"VSS_K32"
$PN"K32"3;
"VSS_K31"
$PN"K31"3;
"VSS_K30"
$PN"K30"3;
"VSS_K29"
$PN"K29"3;
"VSS_K28"
$PN"K28"3;
"VSS_K27"
$PN"K27"3;
"VSS_K26"
$PN"K26"3;
"VSS_K25"
$PN"K25"3;
"VSS_K24"
$PN"K24"3;
"VSS_K19"
$PN"K19"3;
"VSS_K17"
$PN"K17"3;
"VSS_K15"
$PN"K15"3;
"VSS_K12"
$PN"K12"3;
"VSS_K10"
$PN"K10"3;
"VSS_K8"
$PN"K8"3;
"VSS_K5"
$PN"K5"3;
"VSS_K3"
$PN"K3"3;
"VSS_J75"
$PN"J75"3;
"VSS_J72"
$PN"J72"3;
"VSS_J70"
$PN"J70"3;
"VSS_J68"
$PN"J68"3;
"VSS_J65"
$PN"J65"3;
"VSS_J63"
$PN"J63"3;
"VSS_J61"
$PN"J61"3;
"VSS_J58"
$PN"J58"3;
"VSS_J56"
$PN"J56"3;
"VSS_J54"
$PN"J54"3;
"VSS_J51"
$PN"J51"3;
"VSS_J48"
$PN"J48"3;
"VSS_J45"
$PN"J45"3;
"VSS_J42"
$PN"J42"3;
"VSS_J34"
$PN"J34"3;
"VSS_J31"
$PN"J31"3;
"VSS_J28"
$PN"J28"3;
"VSS_J25"
$PN"J25"3;
"VSS_J22"
$PN"J22"3;
"VSS_J20"
$PN"J20"3;
"VSS_J18"
$PN"J18"3;
"VSS_J15"
$PN"J15"3;
"VSS_T64"
$PN"T64"4;
"VSS_T61"
$PN"T61"4;
"VSS_T59"
$PN"T59"4;
"VSS_T57"
$PN"T57"4;
"VSS_T54"
$PN"T54"4;
"VSS_T51"
$PN"T51"4;
"VSS_T48"
$PN"T48"4;
"VSS_T45"
$PN"T45"4;
"VSS_T42"
$PN"T42"4;
"VSS_T39"
$PN"T39"4;
"VSS_T37"
$PN"T37"4;
"VSS_T34"
$PN"T34"4;
"VSS_T31"
$PN"T31"4;
"VSS_T28"
$PN"T28"4;
"VSS_T25"
$PN"T25"4;
"VSS_T22"
$PN"T22"4;
"VSS_T19"
$PN"T19"4;
"VSS_T17"
$PN"T17"4;
"VSS_T15"
$PN"T15"4;
"VSS_T12"
$PN"T12"4;
"VSS_T10"
$PN"T10"4;
"VSS_T8"
$PN"T8"4;
"VSS_T5"
$PN"T5"4;
"VSS_T3"
$PN"T3"4;
"VSS_R75"
$PN"R75"4;
"VSS_R72"
$PN"R72"4;
"VSS_R70"
$PN"R70"4;
"VSS_R68"
$PN"R68"4;
"VSS_R65"
$PN"R65"4;
"VSS_R63"
$PN"R63"4;
"VSS_R61"
$PN"R61"4;
"VSS_R58"
$PN"R58"4;
"VSS_R56"
$PN"R56"4;
"VSS_R54"
$PN"R54"4;
"VSS_R51"
$PN"R51"4;
"VSS_R48"
$PN"R48"4;
%"GENOA_SP5"
"30","(-5600,3450)","0","pure_quanta","I21";
;
LOCATION"U25"
$SEC"30"
CDS_SEC"30"
PART_TYPE"SMLF"
MATERIAL"IO"
VALUE"SOCKET6096_13568-001"
NEEDS_NO_SIZE"TRUE"
CDS_LMAN_SYM_OUTLINE"-400,3050,400,-3050"
CDS_LIB"pure_quanta"
PART_NUMBER"DGA^6000030";
"VSS_AB66"
$PN"AB66"6;
"VSS_AB64"
$PN"AB64"6;
"VSS_AB61"
$PN"AB61"6;
"VSS_AB59"
$PN"AB59"6;
"VSS_AB57"
$PN"AB57"6;
"VSS_AB54"
$PN"AB54"6;
"VSS_AB51"
$PN"AB51"6;
"VSS_AB48"
$PN"AB48"6;
"VSS_AB45"
$PN"AB45"6;
"VSS_AB42"
$PN"AB42"6;
"VSS_AB39"
$PN"AB39"6;
"VSS_AB37"
$PN"AB37"6;
"VSS_AB34"
$PN"AB34"6;
"VSS_AB31"
$PN"AB31"6;
"VSS_AB28"
$PN"AB28"6;
"VSS_AB25"
$PN"AB25"6;
"VSS_AB22"
$PN"AB22"6;
"VSS_AB19"
$PN"AB19"6;
"VSS_AB17"
$PN"AB17"6;
"VSS_AB15"
$PN"AB15"6;
"VSS_AB12"
$PN"AB12"6;
"VSS_AB10"
$PN"AB10"6;
"VSS_AB8"
$PN"AB8"6;
"VSS_AB5"
$PN"AB5"6;
"VSS_AB3"
$PN"AB3"6;
"VSS_AA75"
$PN"AA75"6;
"VSS_AA70"
$PN"AA70"6;
"VSS_AA68"
$PN"AA68"6;
"VSS_AA65"
$PN"AA65"6;
"VSS_AA63"
$PN"AA63"6;
"VSS_AA61"
$PN"AA61"6;
"VSS_AA58"
$PN"AA58"6;
"VSS_AA56"
$PN"AA56"6;
"VSS_AA45"
$PN"AA45"6;
"VSS_AA41"
$PN"AA41"6;
"VSS_AA40"
$PN"AA40"6;
"VSS_AA36"
$PN"AA36"6;
"VSS_AA35"
$PN"AA35"6;
"VSS_AA34"
$PN"AA34"6;
"VSS_AA31"
$PN"AA31"6;
"VSS_AA20"
$PN"AA20"6;
"VSS_AA18"
$PN"AA18"6;
"VSS_AA15"
$PN"AA15"6;
"VSS_AA13"
$PN"AA13"6;
"VSS_AA11"
$PN"AA11"6;
"VSS_AA8"
$PN"AA8"6;
"VSS_AA6"
$PN"AA6"6;
"VSS_AA4"
$PN"AA4"6;
"VSS_AA1"
$PN"AA1"6;
"VSS_Y73"
$PN"Y73"6;
"VSS_Y68"
$PN"Y68"6;
"VSS_Y66"
$PN"Y66"6;
"VSS_Y61"
$PN"Y61"6;
"VSS_Y59"
$PN"Y59"6;
"VSS_Y54"
$PN"Y54"6;
"VSS_Y53"
$PN"Y53"6;
"VSS_Y52"
$PN"Y52"6;
"VSS_Y51"
$PN"Y51"6;
"VSS_Y50"
$PN"Y50"6;
"VSS_Y49"
$PN"Y49"6;
"VSS_Y48"
$PN"Y48"6;
"VSS_Y45"
$PN"Y45"6;
"VSS_Y44"
$PN"Y44"6;
"VSS_Y43"
$PN"Y43"5;
"VSS_Y42"
$PN"Y42"5;
"VSS_Y39"
$PN"Y39"5;
"VSS_Y37"
$PN"Y37"5;
"VSS_Y34"
$PN"Y34"5;
"VSS_Y33"
$PN"Y33"5;
"VSS_Y32"
$PN"Y32"5;
"VSS_Y31"
$PN"Y31"5;
"VSS_Y28"
$PN"Y28"5;
"VSS_Y27"
$PN"Y27"5;
"VSS_Y26"
$PN"Y26"5;
"VSS_Y25"
$PN"Y25"5;
"VSS_Y24"
$PN"Y24"5;
"VSS_Y23"
$PN"Y23"5;
"VSS_Y22"
$PN"Y22"5;
"VSS_Y17"
$PN"Y17"5;
"VSS_Y15"
$PN"Y15"5;
"VSS_Y10"
$PN"Y10"5;
"VSS_Y8"
$PN"Y8"5;
"VSS_Y3"
$PN"Y3"5;
"VSS_W75"
$PN"W75"5;
"VSS_W72"
$PN"W72"5;
"VSS_W70"
$PN"W70"5;
"VSS_W68"
$PN"W68"5;
"VSS_W65"
$PN"W65"5;
"VSS_W63"
$PN"W63"5;
"VSS_W61"
$PN"W61"5;
"VSS_W58"
$PN"W58"5;
"VSS_W56"
$PN"W56"5;
"VSS_W54"
$PN"W54"5;
"VSS_W51"
$PN"W51"5;
"VSS_W48"
$PN"W48"5;
"VSS_W45"
$PN"W45"5;
"VSS_W42"
$PN"W42"5;
"VSS_W41"
$PN"W41"5;
"VSS_W40"
$PN"W40"5;
"VSS_W36"
$PN"W36"5;
"VSS_W35"
$PN"W35"5;
"VSS_W34"
$PN"W34"5;
"VSS_W28"
$PN"W28"5;
"VSS_W25"
$PN"W25"5;
"VSS_W22"
$PN"W22"5;
"VSS_W20"
$PN"W20"5;
"VSS_W18"
$PN"W18"5;
"VSS_W15"
$PN"W15"5;
"VSS_W13"
$PN"W13"5;
"VSS_W11"
$PN"W11"5;
"VSS_W8"
$PN"W8"5;
"VSS_W6"
$PN"W6"5;
"VSS_W4"
$PN"W4"5;
"VSS_W1"
$PN"W1"5;
"VSS_V73"
$PN"V73"5;
"VSS_V71"
$PN"V71"5;
"VSS_V66"
$PN"V66"5;
"VSS_V64"
$PN"V64"5;
"VSS_V61"
$PN"V61"5;
"VSS_V59"
$PN"V59"5;
"VSS_V57"
$PN"V57"5;
"VSS_V53"
$PN"V53"5;
"VSS_V52"
$PN"V52"5;
"VSS_V51"
$PN"V51"5;
"VSS_V50"
$PN"V50"5;
"VSS_V49"
$PN"V49"5;
"VSS_V48"
$PN"V48"5;
"VSS_V47"
$PN"V47"5;
"VSS_V46"
$PN"V46"5;
"VSS_V45"
$PN"V45"5;
"VSS_V44"
$PN"V44"5;
"VSS_V43"
$PN"V43"5;
"VSS_V42"
$PN"V42"5;
"VSS_V39"
$PN"V39"5;
"VSS_V37"
$PN"V37"5;
"VSS_V34"
$PN"V34"5;
"VSS_V33"
$PN"V33"5;
"VSS_V32"
$PN"V32"5;
"VSS_V31"
$PN"V31"5;
"VSS_V30"
$PN"V30"5;
"VSS_V29"
$PN"V29"5;
"VSS_V28"
$PN"V28"5;
"VSS_V26"
$PN"V26"5;
"VSS_V25"
$PN"V25"5;
"VSS_V24"
$PN"V24"5;
"VSS_V23"
$PN"V23"5;
"VSS_V19"
$PN"V19"5;
"VSS_V17"
$PN"V17"5;
"VSS_V15"
$PN"V15"5;
"VSS_V12"
$PN"V12"5;
"VSS_V10"
$PN"V10"5;
"VSS_V8"
$PN"V8"5;
"VSS_V5"
$PN"V5"5;
"VSS_V3"
$PN"V3"5;
"VSS_U75"
$PN"U75"5;
"VSS_U70"
$PN"U70"5;
"VSS_U68"
$PN"U68"5;
"VSS_U63"
$PN"U63"5;
"VSS_U61"
$PN"U61"5;
"VSS_U56"
$PN"U56"5;
"VSS_U54"
$PN"U54"5;
"VSS_U51"
$PN"U51"5;
"VSS_U48"
$PN"U48"5;
"VSS_U45"
$PN"U45"5;
"VSS_U42"
$PN"U42"5;
"VSS_U34"
$PN"U34"5;
"VSS_U31"
$PN"U31"5;
"VSS_U28"
$PN"U28"5;
"VSS_U25"
$PN"U25"5;
"VSS_U22"
$PN"U22"5;
"VSS_U20"
$PN"U20"5;
"VSS_U15"
$PN"U15"5;
"VSS_U13"
$PN"U13"5;
"VSS_U8"
$PN"U8"5;
"VSS_U6"
$PN"U6"5;
"VSS_U1"
$PN"U1"5;
"VSS_T73"
$PN"T73"5;
"VSS_T71"
$PN"T71"5;
"VSS_T68"
$PN"T68"5;
"VSS_T66"
$PN"T66"5;
"VSS_AD48"
$PN"AD48"6;
"VSS_AD47"
$PN"AD47"6;
"VSS_AD46"
$PN"AD46"6;
"VSS_AD45"
$PN"AD45"6;
"VSS_AD44"
$PN"AD44"6;
"VSS_AD43"
$PN"AD43"6;
"VSS_AD42"
$PN"AD42"6;
"VSS_AD39"
$PN"AD39"6;
"VSS_AD37"
$PN"AD37"6;
"VSS_AD34"
$PN"AD34"6;
"VSS_AD33"
$PN"AD33"6;
"VSS_AD32"
$PN"AD32"6;
"VSS_AD30"
$PN"AD30"6;
"VSS_AD29"
$PN"AD29"6;
"VSS_AD28"
$PN"AD28"6;
"VSS_AD27"
$PN"AD27"6;
"VSS_AD26"
$PN"AD26"6;
"VSS_AD25"
$PN"AD25"6;
"VSS_AD24"
$PN"AD24"6;
"VSS_AD23"
$PN"AD23"6;
"VSS_AD19"
$PN"AD19"6;
"VSS_AD17"
$PN"AD17"6;
"VSS_AD15"
$PN"AD15"6;
"VSS_AD12"
$PN"AD12"6;
"VSS_AD10"
$PN"AD10"6;
"VSS_AD8"
$PN"AD8"6;
"VSS_AD5"
$PN"AD5"6;
"VSS_AD3"
$PN"AD3"6;
"VSS_AC75"
$PN"AC75"6;
"VSS_AC70"
$PN"AC70"6;
"VSS_AC68"
$PN"AC68"6;
"VSS_AC63"
$PN"AC63"6;
"VSS_AC61"
$PN"AC61"6;
"VSS_AC56"
$PN"AC56"6;
"VSS_AC54"
$PN"AC54"6;
"VSS_AC51"
$PN"AC51"6;
"VSS_AC48"
$PN"AC48"6;
"VSS_AC45"
$PN"AC45"6;
"VSS_AC42"
$PN"AC42"6;
"VSS_AC34"
$PN"AC34"6;
"VSS_AC31"
$PN"AC31"6;
"VSS_AC28"
$PN"AC28"6;
"VSS_AC25"
$PN"AC25"6;
"VSS_AC22"
$PN"AC22"6;
"VSS_AC20"
$PN"AC20"6;
"VSS_AC15"
$PN"AC15"6;
"VSS_AC13"
$PN"AC13"6;
"VSS_AC8"
$PN"AC8"6;
"VSS_AC6"
$PN"AC6"6;
"VSS_AC1"
$PN"AC1"6;
"VSS_AB73"
$PN"AB73"6;
"VSS_AB71"
$PN"AB71"6;
"VSS_AB68"
$PN"AB68"6;
%"GENOA_SP5"
"31","(-4100,3475)","0","pure_quanta","I22";
;
LOCATION"U25"
$SEC"31"
CDS_SEC"31"
PART_TYPE"SMLF"
MATERIAL"IO"
VALUE"SOCKET6096_13568-001"
NEEDS_NO_SIZE"TRUE"
CDS_LMAN_SYM_OUTLINE"-400,3050,400,-3050"
CDS_LIB"pure_quanta"
PART_NUMBER"DGA^6000030";
"VSS_AK8"
$PN"AK8"8;
"VSS_AK5"
$PN"AK5"8;
"VSS_AK3"
$PN"AK3"8;
"VSS_AJ75"
$PN"AJ75"8;
"VSS_AJ70"
$PN"AJ70"8;
"VSS_AJ68"
$PN"AJ68"8;
"VSS_AJ63"
$PN"AJ63"8;
"VSS_AJ61"
$PN"AJ61"8;
"VSS_AJ56"
$PN"AJ56"8;
"VSS_AJ54"
$PN"AJ54"8;
"VSS_AJ51"
$PN"AJ51"8;
"VSS_AJ48"
$PN"AJ48"8;
"VSS_AJ45"
$PN"AJ45"8;
"VSS_AJ42"
$PN"AJ42"8;
"VSS_AJ41"
$PN"AJ41"8;
"VSS_AJ40"
$PN"AJ40"8;
"VSS_AJ36"
$PN"AJ36"8;
"VSS_AJ35"
$PN"AJ35"8;
"VSS_AJ34"
$PN"AJ34"8;
"VSS_AJ31"
$PN"AJ31"8;
"VSS_AJ28"
$PN"AJ28"8;
"VSS_AJ25"
$PN"AJ25"8;
"VSS_AJ22"
$PN"AJ22"8;
"VSS_AJ20"
$PN"AJ20"8;
"VSS_AJ15"
$PN"AJ15"8;
"VSS_AJ8"
$PN"AJ8"8;
"VSS_AJ6"
$PN"AJ6"8;
"VSS_AJ1"
$PN"AJ1"8;
"VSS_AH73"
$PN"AH73"8;
"VSS_AH71"
$PN"AH71"8;
"VSS_AH68"
$PN"AH68"8;
"VSS_AH66"
$PN"AH66"8;
"VSS_AH64"
$PN"AH64"8;
"VSS_AH61"
$PN"AH61"8;
"VSS_AH59"
$PN"AH59"8;
"VSS_AH57"
$PN"AH57"8;
"VSS_AH53"
$PN"AH53"8;
"VSS_AH52"
$PN"AH52"8;
"VSS_AH51"
$PN"AH51"8;
"VSS_AH50"
$PN"AH50"8;
"VSS_AH49"
$PN"AH49"8;
"VSS_AH48"
$PN"AH48"8;
"VSS_AH47"
$PN"AH47"8;
"VSS_AH46"
$PN"AH46"8;
"VSS_AH45"
$PN"AH45"8;
"VSS_AH44"
$PN"AH44"8;
"VSS_AH43"
$PN"AH43"7;
"VSS_AH42"
$PN"AH42"7;
"VSS_AH39"
$PN"AH39"7;
"VSS_AH37"
$PN"AH37"7;
"VSS_AH34"
$PN"AH34"7;
"VSS_AH32"
$PN"AH32"7;
"VSS_AH31"
$PN"AH31"7;
"VSS_AH30"
$PN"AH30"7;
"VSS_AH29"
$PN"AH29"7;
"VSS_AH28"
$PN"AH28"7;
"VSS_AH27"
$PN"AH27"7;
"VSS_AH26"
$PN"AH26"7;
"VSS_AH25"
$PN"AH25"7;
"VSS_AH24"
$PN"AH24"7;
"VSS_AH23"
$PN"AH23"7;
"VSS_AH19"
$PN"AH19"7;
"VSS_AH17"
$PN"AH17"7;
"VSS_AH15"
$PN"AH15"7;
"VSS_AH12"
$PN"AH12"7;
"VSS_AH10"
$PN"AH10"7;
"VSS_AH8"
$PN"AH8"7;
"VSS_AH5"
$PN"AH5"7;
"VSS_AH3"
$PN"AH3"7;
"VSS_AG75"
$PN"AG75"7;
"VSS_AG72"
$PN"AG72"7;
"VSS_AG70"
$PN"AG70"7;
"VSS_AG68"
$PN"AG68"7;
"VSS_AG65"
$PN"AG65"7;
"VSS_AG63"
$PN"AG63"7;
"VSS_AG61"
$PN"AG61"7;
"VSS_AG58"
$PN"AG58"7;
"VSS_AG56"
$PN"AG56"7;
"VSS_AG54"
$PN"AG54"7;
"VSS_AG51"
$PN"AG51"7;
"VSS_AG48"
$PN"AG48"7;
"VSS_AG45"
$PN"AG45"7;
"VSS_AG42"
$PN"AG42"7;
"VSS_AG34"
$PN"AG34"7;
"VSS_AG31"
$PN"AG31"7;
"VSS_AG28"
$PN"AG28"7;
"VSS_AG25"
$PN"AG25"7;
"VSS_AG22"
$PN"AG22"7;
"VSS_AG20"
$PN"AG20"7;
"VSS_AG18"
$PN"AG18"7;
"VSS_AG15"
$PN"AG15"7;
"VSS_AG13"
$PN"AG13"7;
"VSS_AG11"
$PN"AG11"7;
"VSS_AG8"
$PN"AG8"7;
"VSS_AG6"
$PN"AG6"7;
"VSS_AG4"
$PN"AG4"7;
"VSS_AG1"
$PN"AG1"7;
"VSS_AF73"
$PN"AF73"7;
"VSS_AF68"
$PN"AF68"7;
"VSS_AF66"
$PN"AF66"7;
"VSS_AF61"
$PN"AF61"7;
"VSS_AF59"
$PN"AF59"7;
"VSS_AF54"
$PN"AF54"7;
"VSS_AF51"
$PN"AF51"7;
"VSS_AF48"
$PN"AF48"7;
"VSS_AF45"
$PN"AF45"7;
"VSS_AF42"
$PN"AF42"7;
"VSS_AF39"
$PN"AF39"7;
"VSS_AF37"
$PN"AF37"7;
"VSS_AF34"
$PN"AF34"7;
"VSS_AF31"
$PN"AF31"7;
"VSS_AF28"
$PN"AF28"7;
"VSS_AF25"
$PN"AF25"7;
"VSS_AF22"
$PN"AF22"7;
"VSS_AF17"
$PN"AF17"7;
"VSS_AF15"
$PN"AF15"7;
"VSS_AF10"
$PN"AF10"7;
"VSS_AF8"
$PN"AF8"7;
"VSS_AF3"
$PN"AF3"7;
"VSS_AE75"
$PN"AE75"7;
"VSS_AE72"
$PN"AE72"7;
"VSS_AE70"
$PN"AE70"7;
"VSS_AE68"
$PN"AE68"7;
"VSS_AE65"
$PN"AE65"7;
"VSS_AE63"
$PN"AE63"7;
"VSS_AE61"
$PN"AE61"7;
"VSS_AE58"
$PN"AE58"7;
"VSS_AE56"
$PN"AE56"7;
"VSS_AE54"
$PN"AE54"7;
"VSS_AE51"
$PN"AE51"7;
"VSS_AE48"
$PN"AE48"7;
"VSS_AE45"
$PN"AE45"7;
"VSS_AE42"
$PN"AE42"7;
"VSS_AE41"
$PN"AE41"7;
"VSS_AE40"
$PN"AE40"7;
"VSS_AE36"
$PN"AE36"7;
"VSS_AE35"
$PN"AE35"7;
"VSS_AE34"
$PN"AE34"7;
"VSS_AE31"
$PN"AE31"7;
"VSS_AE28"
$PN"AE28"7;
"VSS_AE25"
$PN"AE25"7;
"VSS_AE22"
$PN"AE22"7;
"VSS_AE20"
$PN"AE20"7;
"VSS_AE18"
$PN"AE18"7;
"VSS_AE15"
$PN"AE15"7;
"VSS_AE13"
$PN"AE13"7;
"VSS_AE11"
$PN"AE11"7;
"VSS_AE8"
$PN"AE8"7;
"VSS_AE6"
$PN"AE6"7;
"VSS_AE1"
$PN"AE1"7;
"VSS_AD73"
$PN"AD73"7;
"VSS_AD71"
$PN"AD71"7;
"VSS_AD68"
$PN"AD68"7;
"VSS_AD66"
$PN"AD66"7;
"VSS_AD64"
$PN"AD64"7;
"VSS_AD61"
$PN"AD61"7;
"VSS_AD59"
$PN"AD59"7;
"VSS_AD57"
$PN"AD57"7;
"VSS_AD53"
$PN"AD53"7;
"VSS_AD52"
$PN"AD52"7;
"VSS_AD51"
$PN"AD51"7;
"VSS_AD50"
$PN"AD50"7;
"VSS_AD49"
$PN"AD49"7;
"VSS_AM39"
$PN"AM39"8;
"VSS_AM34"
$PN"AM34"8;
"VSS_AM33"
$PN"AM33"8;
"VSS_AM32"
$PN"AM32"8;
"VSS_AM31"
$PN"AM31"8;
"VSS_AM30"
$PN"AM30"8;
"VSS_AM29"
$PN"AM29"8;
"VSS_AM28"
$PN"AM28"8;
"VSS_AM27"
$PN"AM27"8;
"VSS_AM26"
$PN"AM26"8;
"VSS_AM25"
$PN"AM25"8;
"VSS_AM24"
$PN"AM24"8;
"VSS_AM23"
$PN"AM23"8;
"VSS_AM17"
$PN"AM17"8;
"VSS_AM15"
$PN"AM15"8;
"VSS_AM10"
$PN"AM10"8;
"VSS_AM8"
$PN"AM8"8;
"VSS_AM3"
$PN"AM3"8;
"VSS_AL75"
$PN"AL75"8;
"VSS_AL72"
$PN"AL72"8;
"VSS_AL70"
$PN"AL70"8;
"VSS_AL68"
$PN"AL68"8;
"VSS_AL65"
$PN"AL65"8;
"VSS_AL63"
$PN"AL63"8;
"VSS_AL61"
$PN"AL61"8;
"VSS_AL58"
$PN"AL58"8;
"VSS_AL56"
$PN"AL56"8;
"VSS_AL54"
$PN"AL54"8;
"VSS_AL51"
$PN"AL51"8;
"VSS_AL48"
$PN"AL48"8;
"VSS_AL45"
$PN"AL45"8;
"VSS_AL42"
$PN"AL42"8;
"VSS_AL34"
$PN"AL34"8;
"VSS_AL31"
$PN"AL31"8;
"VSS_AL28"
$PN"AL28"8;
"VSS_AL25"
$PN"AL25"8;
"VSS_AL22"
$PN"AL22"8;
"VSS_AL20"
$PN"AL20"8;
"VSS_AL18"
$PN"AL18"8;
"VSS_AL15"
$PN"AL15"8;
"VSS_AL13"
$PN"AL13"8;
"VSS_AL11"
$PN"AL11"8;
"VSS_AL8"
$PN"AL8"8;
"VSS_AL6"
$PN"AL6"8;
"VSS_AL4"
$PN"AL4"8;
"VSS_AL1"
$PN"AL1"8;
"VSS_AK73"
$PN"AK73"8;
"VSS_AK71"
$PN"AK71"8;
"VSS_AK68"
$PN"AK68"8;
"VSS_AK66"
$PN"AK66"8;
"VSS_AK64"
$PN"AK64"8;
"VSS_AK61"
$PN"AK61"8;
"VSS_AK59"
$PN"AK59"8;
"VSS_AK57"
$PN"AK57"8;
"VSS_AK54"
$PN"AK54"8;
"VSS_AK51"
$PN"AK51"8;
"VSS_AK48"
$PN"AK48"8;
"VSS_AK45"
$PN"AK45"8;
"VSS_AK42"
$PN"AK42"8;
"VSS_AK39"
$PN"AK39"8;
"VSS_AK37"
$PN"AK37"8;
"VSS_AK34"
$PN"AK34"8;
"VSS_AK31"
$PN"AK31"8;
"VSS_AK28"
$PN"AK28"8;
"VSS_AK25"
$PN"AK25"8;
"VSS_AK22"
$PN"AK22"8;
"VSS_AK19"
$PN"AK19"8;
"VSS_AK17"
$PN"AK17"8;
"VSS_AK15"
$PN"AK15"8;
"VSS_AK12"
$PN"AK12"8;
"VSS_AK10"
$PN"AK10"8;
%"GENOA_SP5"
"32","(-2625,3475)","0","pure_quanta","I23";
;
LOCATION"U25"
$SEC"32"
CDS_SEC"32"
PART_TYPE"SMLF"
MATERIAL"IO"
VALUE"SOCKET6096_13568-001"
NEEDS_NO_SIZE"TRUE"
CDS_LMAN_SYM_OUTLINE"-400,3050,400,-3050"
CDS_LIB"pure_quanta"
PART_NUMBER"DGA^6000030";
"VSS_AW61"
$PN"AW61"10;
"VSS_AW58"
$PN"AW58"10;
"VSS_AW56"
$PN"AW56"10;
"VSS_AW53"
$PN"AW53"10;
"VSS_AW51"
$PN"AW51"10;
"VSS_AW49"
$PN"AW49"10;
"VSS_AW28"
$PN"AW28"10;
"VSS_AW26"
$PN"AW26"10;
"VSS_AW24"
$PN"AW24"10;
"VSS_AW22"
$PN"AW22"10;
"VSS_AW20"
$PN"AW20"10;
"VSS_AW18"
$PN"AW18"10;
"VSS_AW15"
$PN"AW15"10;
"VSS_AW13"
$PN"AW13"10;
"VSS_AW11"
$PN"AW11"10;
"VSS_AW8"
$PN"AW8"10;
"VSS_AW6"
$PN"AW6"10;
"VSS_AW4"
$PN"AW4"10;
"VSS_AW1"
$PN"AW1"10;
"VSS_AV73"
$PN"AV73"10;
"VSS_AV68"
$PN"AV68"10;
"VSS_AV66"
$PN"AV66"10;
"VSS_AV61"
$PN"AV61"10;
"VSS_AV59"
$PN"AV59"10;
"VSS_AV54"
$PN"AV54"10;
"VSS_AV52"
$PN"AV52"10;
"VSS_AV50"
$PN"AV50"10;
"VSS_AV48"
$PN"AV48"10;
"VSS_AV46"
$PN"AV46"10;
"VSS_AV44"
$PN"AV44"10;
"VSS_AV42"
$PN"AV42"10;
"VSS_AV40"
$PN"AV40"10;
"VSS_AV37"
$PN"AV37"10;
"VSS_AV35"
$PN"AV35"10;
"VSS_AV33"
$PN"AV33"10;
"VSS_AV31"
$PN"AV31"10;
"VSS_AV29"
$PN"AV29"10;
"VSS_AV27"
$PN"AV27"10;
"VSS_AV25"
$PN"AV25"10;
"VSS_AV23"
$PN"AV23"10;
"VSS_AV17"
$PN"AV17"10;
"VSS_AV15"
$PN"AV15"10;
"VSS_AV10"
$PN"AV10"10;
"VSS_AV8"
$PN"AV8"10;
"VSS_AV3"
$PN"AV3"10;
"VSS_AU75"
$PN"AU75"10;
"VSS_AU73"
$PN"AU73"10;
"VSS_AU72"
$PN"AU72"10;
"VSS_AU70"
$PN"AU70"10;
"VSS_AU68"
$PN"AU68"10;
"VSS_AU65"
$PN"AU65"10;
"VSS_AU63"
$PN"AU63"10;
"VSS_AU61"
$PN"AU61"10;
"VSS_AU58"
$PN"AU58"10;
"VSS_AU56"
$PN"AU56"10;
"VSS_AU53"
$PN"AU53"10;
"VSS_AU51"
$PN"AU51"10;
"VSS_AU49"
$PN"AU49"10;
"VSS_AU47"
$PN"AU47"10;
"VSS_AU45"
$PN"AU45"10;
"VSS_AU43"
$PN"AU43"10;
"VSS_AU41"
$PN"AU41"10;
"VSS_AU36"
$PN"AU36"10;
"VSS_AU34"
$PN"AU34"10;
"VSS_AU32"
$PN"AU32"10;
"VSS_AU30"
$PN"AU30"10;
"VSS_AU28"
$PN"AU28"10;
"VSS_AU26"
$PN"AU26"10;
"VSS_AU24"
$PN"AU24"10;
"VSS_AU22"
$PN"AU22"10;
"VSS_AU20"
$PN"AU20"10;
"VSS_AU18"
$PN"AU18"10;
"VSS_AU15"
$PN"AU15"10;
"VSS_AU13"
$PN"AU13"10;
"VSS_AU11"
$PN"AU11"10;
"VSS_AU8"
$PN"AU8"10;
"VSS_AU6"
$PN"AU6"10;
"VSS_AU4"
$PN"AU4"10;
"VSS_AU3"
$PN"AU3"10;
"VSS_AU1"
$PN"AU1"10;
"VSS_AT73"
$PN"AT73"10;
"VSS_AT72"
$PN"AT72"10;
"VSS_AT71"
$PN"AT71"10;
"VSS_AT70"
$PN"AT70"10;
"VSS_AT68"
$PN"AT68"10;
"VSS_AT67"
$PN"AT67"10;
"VSS_AT66"
$PN"AT66"10;
"VSS_AT64"
$PN"AT64"10;
"VSS_AT63"
$PN"AT63"10;
"VSS_AT61"
$PN"AT61"10;
"VSS_AT60"
$PN"AT60"10;
"VSS_AT59"
$PN"AT59"10;
"VSS_AT57"
$PN"AT57"10;
"VSS_AT56"
$PN"AT56"10;
"VSS_AT54"
$PN"AT54"10;
"VSS_AT52"
$PN"AT52"10;
"VSS_AT50"
$PN"AT50"10;
"VSS_AT48"
$PN"AT48"10;
"VSS_AT46"
$PN"AT46"10;
"VSS_AT44"
$PN"AT44"10;
"VSS_AT42"
$PN"AT42"10;
"VSS_AT40"
$PN"AT40"10;
"VSS_AT37"
$PN"AT37"10;
"VSS_AT35"
$PN"AT35"10;
"VSS_AT33"
$PN"AT33"10;
"VSS_AT31"
$PN"AT31"10;
"VSS_AT29"
$PN"AT29"10;
"VSS_AT27"
$PN"AT27"10;
"VSS_AT25"
$PN"AT25"10;
"VSS_AT23"
$PN"AT23"10;
"VSS_AT20"
$PN"AT20"10;
"VSS_AT19"
$PN"AT19"10;
"VSS_AT17"
$PN"AT17"10;
"VSS_AT16"
$PN"AT16"10;
"VSS_AT15"
$PN"AT15"10;
"VSS_AT13"
$PN"AT13"10;
"VSS_AT12"
$PN"AT12"10;
"VSS_AT10"
$PN"AT10"10;
"VSS_AT9"
$PN"AT9"10;
"VSS_AT8"
$PN"AT8"9;
"VSS_AT6"
$PN"AT6"9;
"VSS_AT5"
$PN"AT5"9;
"VSS_AT4"
$PN"AT4"9;
"VSS_AT3"
$PN"AT3"9;
"VSS_AR75"
$PN"AR75"9;
"VSS_AR71"
$PN"AR71"9;
"VSS_AR70"
$PN"AR70"9;
"VSS_AR68"
$PN"AR68"9;
"VSS_AR67"
$PN"AR67"9;
"VSS_AR64"
$PN"AR64"9;
"VSS_AR63"
$PN"AR63"9;
"VSS_AR61"
$PN"AR61"9;
"VSS_AR60"
$PN"AR60"9;
"VSS_AR57"
$PN"AR57"9;
"VSS_AR56"
$PN"AR56"9;
"VSS_AR53"
$PN"AR53"9;
"VSS_AR51"
$PN"AR51"9;
"VSS_AR49"
$PN"AR49"9;
"VSS_AR47"
$PN"AR47"9;
"VSS_AR45"
$PN"AR45"9;
"VSS_AR43"
$PN"AR43"9;
"VSS_AR41"
$PN"AR41"9;
"VSS_AR36"
$PN"AR36"9;
"VSS_AR34"
$PN"AR34"9;
"VSS_AR32"
$PN"AR32"9;
"VSS_AR30"
$PN"AR30"9;
"VSS_AR28"
$PN"AR28"9;
"VSS_AR26"
$PN"AR26"9;
"VSS_AR24"
$PN"AR24"9;
"VSS_AR22"
$PN"AR22"9;
"VSS_AR20"
$PN"AR20"9;
"VSS_AR19"
$PN"AR19"9;
"VSS_AR16"
$PN"AR16"9;
"VSS_AR15"
$PN"AR15"9;
"VSS_AR13"
$PN"AR13"9;
"VSS_AR12"
$PN"AR12"9;
"VSS_AR9"
$PN"AR9"9;
"VSS_AR8"
$PN"AR8"9;
"VSS_AR6"
$PN"AR6"9;
"VSS_AR5"
$PN"AR5"9;
"VSS_AR1"
$PN"AR1"9;
"VSS_AP73"
$PN"AP73"9;
"VSS_AP71"
$PN"AP71"9;
"VSS_AP68"
$PN"AP68"9;
"VSS_AP66"
$PN"AP66"9;
"VSS_AP64"
$PN"AP64"9;
"VSS_AP61"
$PN"AP61"9;
"VSS_AP59"
$PN"AP59"9;
"VSS_AP57"
$PN"AP57"9;
"VSS_AP54"
$PN"AP54"9;
"VSS_AP51"
$PN"AP51"9;
"VSS_AP48"
$PN"AP48"9;
"VSS_AP45"
$PN"AP45"9;
"VSS_AP42"
$PN"AP42"9;
"VSS_AP39"
$PN"AP39"9;
"VSS_AP37"
$PN"AP37"9;
"VSS_AP34"
$PN"AP34"9;
"VSS_AP31"
$PN"AP31"9;
"VSS_AP28"
$PN"AP28"9;
"VSS_AP25"
$PN"AP25"9;
"VSS_AP22"
$PN"AP22"9;
"VSS_AP19"
$PN"AP19"9;
"VSS_AP17"
$PN"AP17"9;
"VSS_AP15"
$PN"AP15"9;
"VSS_AP12"
$PN"AP12"9;
"VSS_AP10"
$PN"AP10"9;
"VSS_AP8"
$PN"AP8"9;
"VSS_AP5"
$PN"AP5"9;
"VSS_AP3"
$PN"AP3"9;
"VSS_AN75"
$PN"AN75"9;
"VSS_AN72"
$PN"AN72"9;
"VSS_AN70"
$PN"AN70"9;
"VSS_AN68"
$PN"AN68"9;
"VSS_AN65"
$PN"AN65"9;
"VSS_AN63"
$PN"AN63"9;
"VSS_AN61"
$PN"AN61"9;
"VSS_AN58"
$PN"AN58"9;
"VSS_AN56"
$PN"AN56"9;
"VSS_AN54"
$PN"AN54"9;
"VSS_AN51"
$PN"AN51"9;
"VSS_AN48"
$PN"AN48"9;
"VSS_AN45"
$PN"AN45"9;
"VSS_AN42"
$PN"AN42"9;
"VSS_AN41"
$PN"AN41"9;
"VSS_AN40"
$PN"AN40"9;
"VSS_AN36"
$PN"AN36"9;
"VSS_AN35"
$PN"AN35"9;
"VSS_AN34"
$PN"AN34"9;
"VSS_AN31"
$PN"AN31"9;
"VSS_AN28"
$PN"AN28"9;
"VSS_AN25"
$PN"AN25"9;
"VSS_AN22"
$PN"AN22"9;
"VSS_AN18"
$PN"AN18"9;
"VSS_AN15"
$PN"AN15"9;
"VSS_AN13"
$PN"AN13"9;
"VSS_AN11"
$PN"AN11"9;
"VSS_AN8"
$PN"AN8"9;
"VSS_AN6"
$PN"AN6"9;
"VSS_AN4"
$PN"AN4"9;
"VSS_AN1"
$PN"AN1"9;
"VSS_AM73"
$PN"AM73"9;
"VSS_AM68"
$PN"AM68"9;
"VSS_AM66"
$PN"AM66"9;
"VSS_AM61"
$PN"AM61"9;
"VSS_AM59"
$PN"AM59"9;
"VSS_AM53"
$PN"AM53"9;
"VSS_AM52"
$PN"AM52"9;
"VSS_AM51"
$PN"AM51"9;
"VSS_AM50"
$PN"AM50"9;
"VSS_AM49"
$PN"AM49"9;
"VSS_AM48"
$PN"AM48"9;
"VSS_AM47"
$PN"AM47"9;
"VSS_AM46"
$PN"AM46"9;
"VSS_AM45"
$PN"AM45"9;
"VSS_AM44"
$PN"AM44"9;
"VSS_AM43"
$PN"AM43"9;
"VSS_AM42"
$PN"AM42"9;
%"GENOA_SP5"
"33","(-1000,3475)","0","pure_quanta","I24";
;
LOCATION"U25"
$SEC"33"
CDS_SEC"33"
PART_TYPE"SMLF"
MATERIAL"IO"
VALUE"SOCKET6096_13568-001"
NEEDS_NO_SIZE"TRUE"
CDS_LMAN_SYM_OUTLINE"-400,3050,400,-3050"
CDS_LIB"pure_quanta"
PART_NUMBER"DGA^6000030";
"VSS_BL24"
$PN"BL24"12;
"VSS_BL22"
$PN"BL22"12;
"VSS_BL20"
$PN"BL20"12;
"VSS_BL18"
$PN"BL18"12;
"VSS_BL15"
$PN"BL15"12;
"VSS_BL13"
$PN"BL13"12;
"VSS_BL11"
$PN"BL11"12;
"VSS_BL8"
$PN"BL8"12;
"VSS_BL6"
$PN"BL6"12;
"VSS_BL4"
$PN"BL4"12;
"VSS_BL1"
$PN"BL1"12;
"VSS_BK73"
$PN"BK73"12;
"VSS_BK71"
$PN"BK71"12;
"VSS_BK68"
$PN"BK68"12;
"VSS_BK66"
$PN"BK66"12;
"VSS_BK64"
$PN"BK64"12;
"VSS_BK61"
$PN"BK61"12;
"VSS_BK59"
$PN"BK59"12;
"VSS_BK57"
$PN"BK57"12;
"VSS_BK54"
$PN"BK54"12;
"VSS_BK52"
$PN"BK52"12;
"VSS_BK50"
$PN"BK50"12;
"VSS_BK48"
$PN"BK48"12;
"VSS_BK27"
$PN"BK27"12;
"VSS_BK25"
$PN"BK25"12;
"VSS_BK23"
$PN"BK23"12;
"VSS_BK19"
$PN"BK19"12;
"VSS_BK17"
$PN"BK17"12;
"VSS_BK15"
$PN"BK15"12;
"VSS_BK12"
$PN"BK12"12;
"VSS_BK10"
$PN"BK10"12;
"VSS_BK8"
$PN"BK8"12;
"VSS_BK5"
$PN"BK5"12;
"VSS_BK3"
$PN"BK3"12;
"VSS_BJ75"
$PN"BJ75"12;
"VSS_BJ70"
$PN"BJ70"12;
"VSS_BJ68"
$PN"BJ68"12;
"VSS_BJ63"
$PN"BJ63"12;
"VSS_BJ61"
$PN"BJ61"12;
"VSS_BJ56"
$PN"BJ56"12;
"VSS_BJ53"
$PN"BJ53"12;
"VSS_BJ51"
$PN"BJ51"12;
"VSS_BJ49"
$PN"BJ49"12;
"VSS_BJ28"
$PN"BJ28"12;
"VSS_BJ26"
$PN"BJ26"12;
"VSS_BJ24"
$PN"BJ24"12;
"VSS_BJ22"
$PN"BJ22"12;
"VSS_BJ20"
$PN"BJ20"12;
"VSS_BJ15"
$PN"BJ15"12;
"VSS_BJ13"
$PN"BJ13"12;
"VSS_BJ8"
$PN"BJ8"12;
"VSS_BJ6"
$PN"BJ6"12;
"VSS_BJ1"
$PN"BJ1"12;
"VSS_BH73"
$PN"BH73"12;
"VSS_BH71"
$PN"BH71"12;
"VSS_BH68"
$PN"BH68"12;
"VSS_BH66"
$PN"BH66"12;
"VSS_BH64"
$PN"BH64"12;
"VSS_BH61"
$PN"BH61"12;
"VSS_BH59"
$PN"BH59"12;
"VSS_BH57"
$PN"BH57"12;
"VSS_BH54"
$PN"BH54"12;
"VSS_BH52"
$PN"BH52"12;
"VSS_BH50"
$PN"BH50"12;
"VSS_BH49"
$PN"BH49"12;
"VSS_BH28"
$PN"BH28"12;
"VSS_BH26"
$PN"BH26"12;
"VSS_BH24"
$PN"BH24"12;
"VSS_BH22"
$PN"BH22"12;
"VSS_BH19"
$PN"BH19"12;
"VSS_BH17"
$PN"BH17"12;
"VSS_BH15"
$PN"BH15"12;
"VSS_BH12"
$PN"BH12"12;
"VSS_BH10"
$PN"BH10"12;
"VSS_BH8"
$PN"BH8"12;
"VSS_BH5"
$PN"BH5"12;
"VSS_BH3"
$PN"BH3"12;
"VSS_BG75"
$PN"BG75"12;
"VSS_BG72"
$PN"BG72"12;
"VSS_BG70"
$PN"BG70"12;
"VSS_BG68"
$PN"BG68"12;
"VSS_BG65"
$PN"BG65"12;
"VSS_BG63"
$PN"BG63"12;
"VSS_BG61"
$PN"BG61"12;
"VSS_BG58"
$PN"BG58"12;
"VSS_BG56"
$PN"BG56"12;
"VSS_BG53"
$PN"BG53"12;
"VSS_BG51"
$PN"BG51"12;
"VSS_BG49"
$PN"BG49"12;
"VSS_BG27"
$PN"BG27"12;
"VSS_BG25"
$PN"BG25"12;
"VSS_BG23"
$PN"BG23"12;
"VSS_BG20"
$PN"BG20"12;
"VSS_BG18"
$PN"BG18"12;
"VSS_BG15"
$PN"BG15"12;
"VSS_BG13"
$PN"BG13"12;
"VSS_BG11"
$PN"BG11"12;
"VSS_BG8"
$PN"BG8"12;
"VSS_BG6"
$PN"BG6"12;
"VSS_BG4"
$PN"BG4"12;
"VSS_BG1"
$PN"BG1"12;
"VSS_BF73"
$PN"BF73"12;
"VSS_BF68"
$PN"BF68"12;
"VSS_BF66"
$PN"BF66"12;
"VSS_BF61"
$PN"BF61"12;
"VSS_BF59"
$PN"BF59"12;
"VSS_BF54"
$PN"BF54"12;
"VSS_BF52"
$PN"BF52"12;
"VSS_BF50"
$PN"BF50"12;
"VSS_BF49"
$PN"BF49"12;
"VSS_BF28"
$PN"BF28"12;
"VSS_BF26"
$PN"BF26"12;
"VSS_BF24"
$PN"BF24"12;
"VSS_BF22"
$PN"BF22"12;
"VSS_BF19"
$PN"BF19"12;
"VSS_BF17"
$PN"BF17"12;
"VSS_BF15"
$PN"BF15"12;
"VSS_BF12"
$PN"BF12"12;
"VSS_BF10"
$PN"BF10"12;
"VSS_BF8"
$PN"BF8"11;
"VSS_BF5"
$PN"BF5"11;
"VSS_BF3"
$PN"BF3"11;
"VSS_BD73"
$PN"BD73"11;
"VSS_BD71"
$PN"BD71"11;
"VSS_BD68"
$PN"BD68"11;
"VSS_BD66"
$PN"BD66"11;
"VSS_BD64"
$PN"BD64"11;
"VSS_BD61"
$PN"BD61"11;
"VSS_BD59"
$PN"BD59"11;
"VSS_BD57"
$PN"BD57"11;
"VSS_BD53"
$PN"BD53"11;
"VSS_BD51"
$PN"BD51"11;
"VSS_BD49"
$PN"BD49"11;
"VSS_BD27"
$PN"BD27"11;
"VSS_BD25"
$PN"BD25"11;
"VSS_BD23"
$PN"BD23"11;
"VSS_BD17"
$PN"BD17"11;
"VSS_BD15"
$PN"BD15"11;
"VSS_BD10"
$PN"BD10"11;
"VSS_BD8"
$PN"BD8"11;
"VSS_BD3"
$PN"BD3"11;
"VSS_BC75"
$PN"BC75"11;
"VSS_BC72"
$PN"BC72"11;
"VSS_BC70"
$PN"BC70"11;
"VSS_BC68"
$PN"BC68"11;
"VSS_BC65"
$PN"BC65"11;
"VSS_BC63"
$PN"BC63"11;
"VSS_BC61"
$PN"BC61"11;
"VSS_BC58"
$PN"BC58"11;
"VSS_BC56"
$PN"BC56"11;
"VSS_BC53"
$PN"BC53"11;
"VSS_BC51"
$PN"BC51"11;
"VSS_BC50"
$PN"BC50"11;
"VSS_BC49"
$PN"BC49"11;
"VSS_BC28"
$PN"BC28"11;
"VSS_BC26"
$PN"BC26"11;
"VSS_BC24"
$PN"BC24"11;
"VSS_BC22"
$PN"BC22"11;
"VSS_BC20"
$PN"BC20"11;
"VSS_BC18"
$PN"BC18"11;
"VSS_BC15"
$PN"BC15"11;
"VSS_BC13"
$PN"BC13"11;
"VSS_BC11"
$PN"BC11"11;
"VSS_BC8"
$PN"BC8"11;
"VSS_BC6"
$PN"BC6"11;
"VSS_BC4"
$PN"BC4"11;
"VSS_BC1"
$PN"BC1"11;
"VSS_BB73"
$PN"BB73"11;
"VSS_BB71"
$PN"BB71"11;
"VSS_BB68"
$PN"BB68"11;
"VSS_BB66"
$PN"BB66"11;
"VSS_BB64"
$PN"BB64"11;
"VSS_BB61"
$PN"BB61"11;
"VSS_BB59"
$PN"BB59"11;
"VSS_BB57"
$PN"BB57"11;
"VSS_BB54"
$PN"BB54"11;
"VSS_BB52"
$PN"BB52"11;
"VSS_BB50"
$PN"BB50"11;
"VSS_BB48"
$PN"BB48"11;
"VSS_BB27"
$PN"BB27"11;
"VSS_BB25"
$PN"BB25"11;
"VSS_BB23"
$PN"BB23"11;
"VSS_BB19"
$PN"BB19"11;
"VSS_BB17"
$PN"BB17"11;
"VSS_BB15"
$PN"BB15"11;
"VSS_BB12"
$PN"BB12"11;
"VSS_BB10"
$PN"BB10"11;
"VSS_BB8"
$PN"BB8"11;
"VSS_BB5"
$PN"BB5"11;
"VSS_BB3"
$PN"BB3"11;
"VSS_BA75"
$PN"BA75"11;
"VSS_BA70"
$PN"BA70"11;
"VSS_BA68"
$PN"BA68"11;
"VSS_BA63"
$PN"BA63"11;
"VSS_BA61"
$PN"BA61"11;
"VSS_BA56"
$PN"BA56"11;
"VSS_BA53"
$PN"BA53"11;
"VSS_BA51"
$PN"BA51"11;
"VSS_BA49"
$PN"BA49"11;
"VSS_BA28"
$PN"BA28"11;
"VSS_BA26"
$PN"BA26"11;
"VSS_BA24"
$PN"BA24"11;
"VSS_BA22"
$PN"BA22"11;
"VSS_BA20"
$PN"BA20"11;
"VSS_BA15"
$PN"BA15"11;
"VSS_BA13"
$PN"BA13"11;
"VSS_BA8"
$PN"BA8"11;
"VSS_BA6"
$PN"BA6"11;
"VSS_BA1"
$PN"BA1"11;
"VSS_AY73"
$PN"AY73"11;
"VSS_AY71"
$PN"AY71"11;
"VSS_AY68"
$PN"AY68"11;
"VSS_AY66"
$PN"AY66"11;
"VSS_AY64"
$PN"AY64"11;
"VSS_AY61"
$PN"AY61"11;
"VSS_AY59"
$PN"AY59"11;
"VSS_AY57"
$PN"AY57"11;
"VSS_AY54"
$PN"AY54"11;
"VSS_AY52"
$PN"AY52"11;
"VSS_AY50"
$PN"AY50"11;
"VSS_AY48"
$PN"AY48"11;
"VSS_AY27"
$PN"AY27"11;
"VSS_AY25"
$PN"AY25"11;
"VSS_AY23"
$PN"AY23"11;
"VSS_AY19"
$PN"AY19"11;
"VSS_AY17"
$PN"AY17"11;
"VSS_AY15"
$PN"AY15"11;
"VSS_AY12"
$PN"AY12"11;
"VSS_AY10"
$PN"AY10"11;
"VSS_AY8"
$PN"AY8"11;
"VSS_AY5"
$PN"AY5"11;
"VSS_AY3"
$PN"AY3"11;
"VSS_AW75"
$PN"AW75"11;
"VSS_AW72"
$PN"AW72"11;
"VSS_AW70"
$PN"AW70"11;
"VSS_AW68"
$PN"AW68"11;
"VSS_AW65"
$PN"AW65"11;
"VSS_AW63"
$PN"AW63"11;
%"UNIVERSAL_GND"
"1","(-9275,350)","0","pure_quanta_power","I39";
;
CDS_LIB"pure_quanta_power"
HDL_POWER"GND";
"A"1;
%"UNIVERSAL_GND"
"1","(-7750,375)","0","pure_quanta_power","I40";
;
CDS_LIB"pure_quanta_power"
HDL_POWER"GND";
"A"3;
%"UNIVERSAL_GND"
"1","(-6275,400)","0","pure_quanta_power","I41";
;
CDS_LIB"pure_quanta_power"
HDL_POWER"GND";
"A"5;
%"UNIVERSAL_GND"
"1","(-3275,425)","0","pure_quanta_power","I43";
;
CDS_LIB"pure_quanta_power"
HDL_POWER"GND";
"A"9;
%"UNIVERSAL_GND"
"1","(-1650,450)","0","pure_quanta_power","I44";
;
CDS_LIB"pure_quanta_power"
HDL_POWER"GND";
"A"11;
%"UNIVERSAL_GND"
"1","(-7925,375)","0","pure_quanta_power","I45";
;
CDS_LIB"pure_quanta_power"
HDL_POWER"GND";
"A"2;
%"UNIVERSAL_GND"
"1","(-6400,400)","0","pure_quanta_power","I46";
;
CDS_LIB"pure_quanta_power"
HDL_POWER"GND";
"A"4;
%"UNIVERSAL_GND"
"1","(-4925,475)","0","pure_quanta_power","I47";
;
CDS_LIB"pure_quanta_power"
HDL_POWER"GND";
"A"6;
%"UNIVERSAL_GND"
"1","(-3425,500)","0","pure_quanta_power","I48";
;
CDS_LIB"pure_quanta_power"
HDL_POWER"GND";
"A"8;
%"UNIVERSAL_GND"
"1","(-1950,450)","0","pure_quanta_power","I49";
;
CDS_LIB"pure_quanta_power"
HDL_POWER"GND";
"A"10;
%"UNIVERSAL_GND"
"1","(-325,450)","0","pure_quanta_power","I50";
;
CDS_LIB"pure_quanta_power"
HDL_POWER"GND";
"A"12;
%"UNIVERSAL_GND"
"1","(-4775,475)","0","pure_quanta_power","I51";
;
CDS_LIB"pure_quanta_power"
HDL_POWER"GND";
"A"7;
END.
